(kicad_pcb
	(version 20211014)
	(generator pcbnew)
	(general
    (thickness 1.6)
  )
	(paper "A4")
	(title_block
    (title "SI test board")
    (rev "1.0.1")
    (company "Antmicro")
		(comment 9 "footprints 6-12 of 27")
	)
	(layers
    (0 "F.Cu" signal)
    (1 "In1.Cu" signal)
    (2 "In2.Cu" signal)
    (31 "B.Cu" signal)
    (32 "B.Adhes" user "B.Adhesive")
    (33 "F.Adhes" user "F.Adhesive")
    (34 "B.Paste" user)
    (35 "F.Paste" user)
    (36 "B.SilkS" user "B.Silkscreen")
    (37 "F.SilkS" user "F.Silkscreen")
    (38 "B.Mask" user)
    (39 "F.Mask" user)
    (40 "Dwgs.User" user "User.Drawings")
    (41 "Cmts.User" user "User.Comments")
    (42 "Eco1.User" user "User.Eco1")
    (43 "Eco2.User" user "User.Eco2")
    (44 "Edge.Cuts" user)
    (45 "Margin" user)
    (46 "B.CrtYd" user "B.Courtyard")
    (47 "F.CrtYd" user "F.Courtyard")
    (48 "B.Fab" user)
    (49 "F.Fab" user)
  )
	(footprint "si-simulation-test-board-footprints:RF_SMA_BoardEdge_RF2-143-T-17-50-G" (layer "F.Cu")
    (tedit 64FEFFC5)
    (at 146.63 66.0005 -90)
    (descr "RF SMA SMD board edge connector")
    (property "Author" "Antmicro")
    (property "License" "Apache-2.0")
    (property "MPN" "RF2-143-T-17-50-G")
    (property "Manufacturer" "ADAM TECH")
    (property "Sheetfile" "si-simulation-test-board.kicad_sch")
    (property "Sheetname" "")
    (attr smd)
    (fp_text reference "J3" (at -4.5 6.88) (layer "F.SilkS")
      (effects (font (size 0.7 0.7) (thickness 0.15)) (justify left bottom))
    )
    (fp_text value "Conn_SMA_RF2-143-T-17-50-G" (at 0 9.24 -90) (layer "F.Fab")
      (effects (font (size 0.7 0.7) (thickness 0.15)) (justify left bottom))
    )
    (fp_text user "License: Apache-2.0" (at -4.5 12.44 -90) (layer "F.Fab") hide
      (effects (font (size 0.7 0.7) (thickness 0.15)) (justify left bottom))
    )
    (fp_text user "Author: Antmicro" (at -4.5 11.24 -90) (layer "F.Fab") hide
      (effects (font (size 0.7 0.7) (thickness 0.15)) (justify left bottom))
    )
    (fp_text user "${REFERENCE}" (at -4.5 13.64 -90) (layer "F.Fab") hide
      (effects (font (size 0.7 0.7) (thickness 0.15)) (justify left bottom))
    )
    (fp_rect (start -3.995 -7.53) (end 3.995 7.53) (layer "B.CrtYd") (width 0.05) (fill none))
    (fp_rect (start -3.995 -7.53) (end 3.995 7.53) (layer "F.CrtYd") (width 0.05) (fill none))
    (fp_line (start 0.38 2.654) (end 0.375 6.455) (layer "F.Fab") (width 0.15))
    (fp_line (start 3.174 2.654) (end -3.15 2.654) (layer "F.Fab") (width 0.15))
    (fp_line (start -2.375 2.678) (end -2.375 6.455) (layer "F.Fab") (width 0.15))
    (fp_line (start -3.174 6.455) (end -3.174 1.504) (layer "F.Fab") (width 0.15))
    (fp_line (start 3.174 6.455) (end 3.174 1.504) (layer "F.Fab") (width 0.15))
    (fp_line (start 2.65 -6.375) (end -2.65 -6.375) (layer "F.Fab") (width 0.15))
    (fp_line (start 2.375 6.455) (end 2.375 2.678) (layer "F.Fab") (width 0.15))
    (fp_line (start 2.65 -6.375) (end 2.65 1.504) (layer "F.Fab") (width 0.15))
    (fp_line (start -0.38 2.654) (end -0.38 6.455) (layer "F.Fab") (width 0.15))
    (fp_line (start 0.375 6.455) (end -0.38 6.455) (layer "F.Fab") (width 0.15))
    (fp_line (start -2.65 -6.375) (end -2.65 1.504) (layer "F.Fab") (width 0.15))
    (fp_line (start -2.375 6.455) (end -3.174 6.455) (layer "F.Fab") (width 0.15))
    (fp_line (start 3.174 6.455) (end 2.375 6.455) (layer "F.Fab") (width 0.15))
    (fp_line (start 3.174 1.504) (end -3.174 1.504) (layer "F.Fab") (width 0.15))
    (pad "1" smd rect (at 0.007 4.955 270) (size 2.29 4.191) (layers "F.Cu" "F.Paste" "F.Mask")
      (net 3 "unconnected-(J3-Pad1)") (pinfunction "1") (pintype "passive+no_connect"))
    (pad "2" smd rect (at 2.975 4.955 270) (size 1.45 4.191) (layers "B.Cu" "B.Paste" "B.Mask")
      (net 2 "GND") (pinfunction "2") (pintype "passive"))
    (pad "2" smd rect (at 2.975 4.955 270) (size 1.45 4.191) (layers "F.Cu" "F.Paste" "F.Mask")
      (net 2 "GND") (pinfunction "2") (pintype "passive"))
    (pad "2" smd rect (at -2.975 4.955 270) (size 1.45 4.191) (layers "F.Cu" "F.Paste" "F.Mask")
      (net 2 "GND") (pinfunction "2") (pintype "passive"))
    (pad "2" smd rect (at -2.975 4.955 270) (size 1.45 4.191) (layers "B.Cu" "B.Paste" "B.Mask")
      (net 2 "GND") (pinfunction "2") (pintype "passive"))
  )
	(footprint "si-simulation-test-board-footprints:RF_SMA_BoardEdge_RF2-143-T-17-50-G" (layer "F.Cu")
    (tedit 64FEFFC5)
    (at 146.68 147.6155 -90)
    (descr "RF SMA SMD board edge connector")
    (property "Author" "Antmicro")
    (property "License" "Apache-2.0")
    (property "MPN" "RF2-143-T-17-50-G")
    (property "Manufacturer" "ADAM TECH")
    (property "Sheetfile" "si-simulation-test-board.kicad_sch")
    (property "Sheetname" "")
    (attr smd)
    (fp_text reference "J18" (at -4.5 6.88) (layer "F.SilkS")
      (effects (font (size 0.7 0.7) (thickness 0.15)) (justify left bottom))
    )
    (fp_text value "Conn_SMA_RF2-143-T-17-50-G" (at 0 9.24 -90) (layer "F.Fab")
      (effects (font (size 0.7 0.7) (thickness 0.15)) (justify left bottom))
    )
    (fp_text user "${REFERENCE}" (at -4.5 13.64 -90) (layer "F.Fab") hide
      (effects (font (size 0.7 0.7) (thickness 0.15)) (justify left bottom))
    )
    (fp_text user "License: Apache-2.0" (at -4.5 12.44 -90) (layer "F.Fab") hide
      (effects (font (size 0.7 0.7) (thickness 0.15)) (justify left bottom))
    )
    (fp_text user "Author: Antmicro" (at -4.5 11.24 -90) (layer "F.Fab") hide
      (effects (font (size 0.7 0.7) (thickness 0.15)) (justify left bottom))
    )
    (fp_rect (start -3.995 -7.53) (end 3.995 7.53) (layer "B.CrtYd") (width 0.05) (fill none))
    (fp_rect (start -3.995 -7.53) (end 3.995 7.53) (layer "F.CrtYd") (width 0.05) (fill none))
    (fp_line (start 0.375 6.455) (end -0.38 6.455) (layer "F.Fab") (width 0.15))
    (fp_line (start 3.174 6.455) (end 3.174 1.504) (layer "F.Fab") (width 0.15))
    (fp_line (start -0.38 2.654) (end -0.38 6.455) (layer "F.Fab") (width 0.15))
    (fp_line (start 3.174 6.455) (end 2.375 6.455) (layer "F.Fab") (width 0.15))
    (fp_line (start 2.65 -6.375) (end -2.65 -6.375) (layer "F.Fab") (width 0.15))
    (fp_line (start -2.65 -6.375) (end -2.65 1.504) (layer "F.Fab") (width 0.15))
    (fp_line (start 2.65 -6.375) (end 2.65 1.504) (layer "F.Fab") (width 0.15))
    (fp_line (start 3.174 2.654) (end -3.15 2.654) (layer "F.Fab") (width 0.15))
    (fp_line (start -3.174 6.455) (end -3.174 1.504) (layer "F.Fab") (width 0.15))
    (fp_line (start 0.38 2.654) (end 0.375 6.455) (layer "F.Fab") (width 0.15))
    (fp_line (start -2.375 6.455) (end -3.174 6.455) (layer "F.Fab") (width 0.15))
    (fp_line (start 3.174 1.504) (end -3.174 1.504) (layer "F.Fab") (width 0.15))
    (fp_line (start 2.375 6.455) (end 2.375 2.678) (layer "F.Fab") (width 0.15))
    (fp_line (start -2.375 2.678) (end -2.375 6.455) (layer "F.Fab") (width 0.15))
    (pad "1" smd rect (at 0.007 4.955 270) (size 2.29 4.191) (layers "F.Cu" "F.Paste" "F.Mask")
      (net 10 "Net-(J16-Pad1)") (pinfunction "1") (pintype "passive"))
    (pad "2" smd rect (at 2.975 4.955 270) (size 1.45 4.191) (layers "B.Cu" "B.Paste" "B.Mask")
      (net 2 "GND") (pinfunction "2") (pintype "passive"))
    (pad "2" smd rect (at 2.975 4.955 270) (size 1.45 4.191) (layers "F.Cu" "F.Paste" "F.Mask")
      (net 2 "GND") (pinfunction "2") (pintype "passive"))
    (pad "2" smd rect (at -2.975 4.955 270) (size 1.45 4.191) (layers "F.Cu" "F.Paste" "F.Mask")
      (net 2 "GND") (pinfunction "2") (pintype "passive"))
    (pad "2" smd rect (at -2.975 4.955 270) (size 1.45 4.191) (layers "B.Cu" "B.Paste" "B.Mask")
      (net 2 "GND") (pinfunction "2") (pintype "passive"))
  )
	(footprint "si-simulation-test-board-footprints:C_0402_1005Metric" (layer "F.Cu")
    (tedit 616D63CF)
    (at 112.39 146.415)
    (descr "Capacitor SMD 0402")
    (tags "capacitor SMD 0402")
    (property "Author" "Antmicro")
    (property "Dielectric" "X5R")
    (property "License" "Apache-2.0")
    (property "MPN" "GRM155R61H104KE14D")
    (property "Manufacturer" "Murata")
    (property "Sheetfile" "si-simulation-test-board.kicad_sch")
    (property "Sheetname" "")
    (property "Val" "100n")
    (property "Voltage" "50V")
    (attr smd)
    (fp_text reference "C2" (at 0.001 -0.7) (layer "F.SilkS") hide
      (effects (font (size 0.7 0.7) (thickness 0.15)) (justify left bottom))
    )
    (fp_text value "C_100n_0402" (at 0 1.4) (layer "F.Fab")
      (effects (font (size 0.7 0.7) (thickness 0.15)) (justify left bottom))
    )
    (fp_text user "License: Apache-2.0" (at -0.932 5.17) (layer "F.Fab") hide
      (effects (font (size 0.7 0.7) (thickness 0.15)) (justify left bottom))
    )
    (fp_text user "Author: Antmicro" (at -0.932 4.17) (layer "F.Fab") hide
      (effects (font (size 0.7 0.7) (thickness 0.15)) (justify left bottom))
    )
    (fp_text user "${REFERENCE}" (at -0.932 3.168) (layer "F.Fab") hide
      (effects (font (size 0.7 0.7) (thickness 0.15)) (justify left bottom))
    )
    (fp_rect (start -0.94 -0.47) (end 0.94 0.47) (layer "F.CrtYd") (width 0.05) (fill none))
    (fp_rect (start -0.499 -0.249) (end 0.499 0.249) (layer "F.Fab") (width 0.15) (fill none))
    (pad "1" smd roundrect (at -0.484 0) (size 0.59 0.64) (layers "F.Cu" "F.Paste" "F.Mask") (roundrect_rratio 0.25)
      (net 2 "GND") (pintype "passive"))
    (pad "2" smd roundrect (at 0.484 0) (size 0.59 0.64) (layers "F.Cu" "F.Paste" "F.Mask") (roundrect_rratio 0.25)
      (net 2 "GND") (pintype "passive"))
  )
	(footprint "si-simulation-test-board-footprints:R_0402_1005Metric" (layer "F.Cu")
    (tedit 5FD9C158)
    (at 101.45 56.007499)
    (descr "Resistor SMD 0402")
    (tags "resistor SMD 0402")
    (property "Author" "Antmicro")
    (property "License" "Apache-2.0")
    (property "MPN" "CR0402-FX-50R0GLF")
    (property "Manufacturer" "Bourns")
    (property "Sheetfile" "si-simulation-test-board.kicad_sch")
    (property "Sheetname" "")
    (property "Tolerance" "1%")
    (property "Val" "50R")
    (attr smd)
    (fp_text reference "R2" (at 0 -0.7) (layer "F.SilkS") hide
      (effects (font (size 0.7 0.7) (thickness 0.15)) (justify left bottom))
    )
    (fp_text value "R_50R_0402" (at 0 1.4) (layer "F.Fab")
      (effects (font (size 0.7 0.7) (thickness 0.15)) (justify left bottom))
    )
    (fp_text user "Author: Antmicro" (at -0.95 4.169) (layer "F.Fab") hide
      (effects (font (size 0.7 0.7) (thickness 0.15)) (justify left bottom))
    )
    (fp_text user "${REFERENCE}" (at -0.95 3.168) (layer "F.Fab") hide
      (effects (font (size 0.7 0.7) (thickness 0.15)) (justify left bottom))
    )
    (fp_text user "License: Apache-2.0" (at -0.95 5.169) (layer "F.Fab") hide
      (effects (font (size 0.7 0.7) (thickness 0.15)) (justify left bottom))
    )
    (fp_rect (start -0.93 -0.47) (end 0.93 0.47) (layer "F.CrtYd") (width 0.05) (fill none))
    (fp_rect (start -0.5 -0.25) (end 0.5 0.25) (layer "F.Fab") (width 0.15) (fill none))
    (pad "1" smd roundrect (at -0.485 0) (size 0.59 0.64) (layers "F.Cu" "F.Paste" "F.Mask") (roundrect_rratio 0.25)
      (net 11 "Net-(J6-Pad1)") (pintype "passive"))
    (pad "2" smd roundrect (at 0.485 0) (size 0.59 0.64) (layers "F.Cu" "F.Paste" "F.Mask") (roundrect_rratio 0.25)
      (net 2 "GND") (pintype "passive"))
  )
	(footprint "si-simulation-test-board-footprints:C_0402_1005Metric" (layer "F.Cu")
    (tedit 616D63CF)
    (at 126.62 146.345)
    (descr "Capacitor SMD 0402")
    (tags "capacitor SMD 0402")
    (property "Author" "Antmicro")
    (property "Dielectric" "X5R")
    (property "License" "Apache-2.0")
    (property "MPN" "GRM155R61H104KE14D")
    (property "Manufacturer" "Murata")
    (property "Sheetfile" "si-simulation-test-board.kicad_sch")
    (property "Sheetname" "")
    (property "Val" "100n")
    (property "Voltage" "50V")
    (attr smd)
    (fp_text reference "C1" (at 0.001 -0.7) (layer "F.SilkS") hide
      (effects (font (size 0.7 0.7) (thickness 0.15)) (justify left bottom))
    )
    (fp_text value "C_100n_0402" (at 0 1.4) (layer "F.Fab")
      (effects (font (size 0.7 0.7) (thickness 0.15)) (justify left bottom))
    )
    (fp_text user "${REFERENCE}" (at -0.932 3.168) (layer "F.Fab") hide
      (effects (font (size 0.7 0.7) (thickness 0.15)) (justify left bottom))
    )
    (fp_text user "Author: Antmicro" (at -0.932 4.17) (layer "F.Fab") hide
      (effects (font (size 0.7 0.7) (thickness 0.15)) (justify left bottom))
    )
    (fp_text user "License: Apache-2.0" (at -0.932 5.17) (layer "F.Fab") hide
      (effects (font (size 0.7 0.7) (thickness 0.15)) (justify left bottom))
    )
    (fp_rect (start -0.94 -0.47) (end 0.94 0.47) (layer "F.CrtYd") (width 0.05) (fill none))
    (fp_rect (start -0.499 -0.249) (end 0.499 0.249) (layer "F.Fab") (width 0.15) (fill none))
    (pad "1" smd roundrect (at -0.484 0) (size 0.59 0.64) (layers "F.Cu" "F.Paste" "F.Mask") (roundrect_rratio 0.25)
      (net 2 "GND") (pintype "passive"))
    (pad "2" smd roundrect (at 0.484 0) (size 0.59 0.64) (layers "F.Cu" "F.Paste" "F.Mask") (roundrect_rratio 0.25)
      (net 2 "GND") (pintype "passive"))
  )
	(footprint "si-simulation-test-board-footprints:RF_SMA_BoardEdge_RF2-143-T-17-50-G" (layer "F.Cu")
    (tedit 64FEFFC5)
    (at 146.68 96.0005 -90)
    (descr "RF SMA SMD board edge connector")
    (property "Author" "Antmicro")
    (property "License" "Apache-2.0")
    (property "MPN" "RF2-143-T-17-50-G")
    (property "Manufacturer" "ADAM TECH")
    (property "Sheetfile" "si-simulation-test-board.kicad_sch")
    (property "Sheetname" "")
    (attr smd)
    (fp_text reference "J10" (at -4.5 6.88) (layer "F.SilkS")
      (effects (font (size 0.7 0.7) (thickness 0.15)) (justify left bottom))
    )
    (fp_text value "Conn_SMA_RF2-143-T-17-50-G" (at 0 9.24 -90) (layer "F.Fab")
      (effects (font (size 0.7 0.7) (thickness 0.15)) (justify left bottom))
    )
    (fp_text user "Author: Antmicro" (at -4.5 11.24 -90) (layer "F.Fab") hide
      (effects (font (size 0.7 0.7) (thickness 0.15)) (justify left bottom))
    )
    (fp_text user "License: Apache-2.0" (at -4.5 12.44 -90) (layer "F.Fab") hide
      (effects (font (size 0.7 0.7) (thickness 0.15)) (justify left bottom))
    )
    (fp_text user "${REFERENCE}" (at -4.5 13.64 -90) (layer "F.Fab") hide
      (effects (font (size 0.7 0.7) (thickness 0.15)) (justify left bottom))
    )
    (fp_rect (start -3.995 -7.53) (end 3.995 7.53) (layer "B.CrtYd") (width 0.05) (fill none))
    (fp_rect (start -3.995 -7.53) (end 3.995 7.53) (layer "F.CrtYd") (width 0.05) (fill none))
    (fp_line (start -2.65 -6.375) (end -2.65 1.504) (layer "F.Fab") (width 0.15))
    (fp_line (start 0.38 2.654) (end 0.375 6.455) (layer "F.Fab") (width 0.15))
    (fp_line (start -3.174 6.455) (end -3.174 1.504) (layer "F.Fab") (width 0.15))
    (fp_line (start 3.174 2.654) (end -3.15 2.654) (layer "F.Fab") (width 0.15))
    (fp_line (start -2.375 6.455) (end -3.174 6.455) (layer "F.Fab") (width 0.15))
    (fp_line (start 0.375 6.455) (end -0.38 6.455) (layer "F.Fab") (width 0.15))
    (fp_line (start 3.174 6.455) (end 3.174 1.504) (layer "F.Fab") (width 0.15))
    (fp_line (start 3.174 1.504) (end -3.174 1.504) (layer "F.Fab") (width 0.15))
    (fp_line (start -0.38 2.654) (end -0.38 6.455) (layer "F.Fab") (width 0.15))
    (fp_line (start 2.65 -6.375) (end -2.65 -6.375) (layer "F.Fab") (width 0.15))
    (fp_line (start 3.174 6.455) (end 2.375 6.455) (layer "F.Fab") (width 0.15))
    (fp_line (start 2.375 6.455) (end 2.375 2.678) (layer "F.Fab") (width 0.15))
    (fp_line (start 2.65 -6.375) (end 2.65 1.504) (layer "F.Fab") (width 0.15))
    (fp_line (start -2.375 2.678) (end -2.375 6.455) (layer "F.Fab") (width 0.15))
    (pad "1" smd rect (at 0.007 4.955 270) (size 2.29 4.191) (layers "F.Cu" "F.Paste" "F.Mask")
      (net 6 "Net-(J10-Pad1)") (pinfunction "1") (pintype "passive"))
    (pad "2" smd rect (at -2.975 4.955 270) (size 1.45 4.191) (layers "B.Cu" "B.Paste" "B.Mask")
      (net 2 "GND") (pinfunction "2") (pintype "passive"))
    (pad "2" smd rect (at 2.975 4.955 270) (size 1.45 4.191) (layers "B.Cu" "B.Paste" "B.Mask")
      (net 2 "GND") (pinfunction "2") (pintype "passive"))
    (pad "2" smd rect (at 2.975 4.955 270) (size 1.45 4.191) (layers "F.Cu" "F.Paste" "F.Mask")
      (net 2 "GND") (pinfunction "2") (pintype "passive"))
    (pad "2" smd rect (at -2.975 4.955 270) (size 1.45 4.191) (layers "F.Cu" "F.Paste" "F.Mask")
      (net 2 "GND") (pinfunction "2") (pintype "passive"))
  )
	(footprint "si-simulation-test-board-footprints:RF_SMA_BoardEdge_RF2-143-T-17-50-G" (layer "F.Cu")
    (tedit 64FEFFC5)
    (at 91.37 105.999499 90)
    (descr "RF SMA SMD board edge connector")
    (property "Author" "Antmicro")
    (property "License" "Apache-2.0")
    (property "MPN" "RF2-143-T-17-50-G")
    (property "Manufacturer" "ADAM TECH")
    (property "Sheetfile" "si-simulation-test-board.kicad_sch")
    (property "Sheetname" "")
    (attr smd)
    (fp_text reference "J11" (at -4.5 6.88 180) (layer "F.SilkS")
      (effects (font (size 0.7 0.7) (thickness 0.15)) (justify left bottom))
    )
    (fp_text value "Conn_SMA_RF2-143-T-17-50-G" (at 0 9.24 90) (layer "F.Fab")
      (effects (font (size 0.7 0.7) (thickness 0.15)) (justify left bottom))
    )
    (fp_text user "License: Apache-2.0" (at -4.5 12.44 90) (layer "F.Fab") hide
      (effects (font (size 0.7 0.7) (thickness 0.15)) (justify left bottom))
    )
    (fp_text user "${REFERENCE}" (at -4.5 13.64 90) (layer "F.Fab") hide
      (effects (font (size 0.7 0.7) (thickness 0.15)) (justify left bottom))
    )
    (fp_text user "Author: Antmicro" (at -4.5 11.24 90) (layer "F.Fab") hide
      (effects (font (size 0.7 0.7) (thickness 0.15)) (justify left bottom))
    )
    (fp_rect (start -3.995 -7.53) (end 3.995 7.53) (layer "B.CrtYd") (width 0.05) (fill none))
    (fp_rect (start -3.995 -7.53) (end 3.995 7.53) (layer "F.CrtYd") (width 0.05) (fill none))
    (fp_line (start 3.174 1.504) (end -3.174 1.504) (layer "F.Fab") (width 0.15))
    (fp_line (start 3.174 6.455) (end 2.375 6.455) (layer "F.Fab") (width 0.15))
    (fp_line (start 3.174 6.455) (end 3.174 1.504) (layer "F.Fab") (width 0.15))
    (fp_line (start 3.174 2.654) (end -3.15 2.654) (layer "F.Fab") (width 0.15))
    (fp_line (start -0.38 2.654) (end -0.38 6.455) (layer "F.Fab") (width 0.15))
    (fp_line (start 2.65 -6.375) (end 2.65 1.504) (layer "F.Fab") (width 0.15))
    (fp_line (start -2.65 -6.375) (end -2.65 1.504) (layer "F.Fab") (width 0.15))
    (fp_line (start 0.38 2.654) (end 0.375 6.455) (layer "F.Fab") (width 0.15))
    (fp_line (start -2.375 6.455) (end -3.174 6.455) (layer "F.Fab") (width 0.15))
    (fp_line (start -2.375 2.678) (end -2.375 6.455) (layer "F.Fab") (width 0.15))
    (fp_line (start 2.375 6.455) (end 2.375 2.678) (layer "F.Fab") (width 0.15))
    (fp_line (start -3.174 6.455) (end -3.174 1.504) (layer "F.Fab") (width 0.15))
    (fp_line (start 2.65 -6.375) (end -2.65 -6.375) (layer "F.Fab") (width 0.15))
    (fp_line (start 0.375 6.455) (end -0.38 6.455) (layer "F.Fab") (width 0.15))
    (pad "1" smd rect (at 0.007 4.955 90) (size 2.29 4.191) (layers "F.Cu" "F.Paste" "F.Mask")
      (net 7 "/DIFF_P") (pinfunction "1") (pintype "passive"))
    (pad "2" smd rect (at 2.975 4.955 90) (size 1.45 4.191) (layers "B.Cu" "B.Paste" "B.Mask")
      (net 2 "GND") (pinfunction "2") (pintype "passive"))
    (pad "2" smd rect (at 2.975 4.955 90) (size 1.45 4.191) (layers "F.Cu" "F.Paste" "F.Mask")
      (net 2 "GND") (pinfunction "2") (pintype "passive"))
    (pad "2" smd rect (at -2.975 4.955 90) (size 1.45 4.191) (layers "B.Cu" "B.Paste" "B.Mask")
      (net 2 "GND") (pinfunction "2") (pintype "passive"))
    (pad "2" smd rect (at -2.975 4.955 90) (size 1.45 4.191) (layers "F.Cu" "F.Paste" "F.Mask")
      (net 2 "GND") (pinfunction "2") (pintype "passive"))
  )
)
